# T6G (Grand Teton) — schematic netlist excerpt (pin names and nets, part order shuffled) for the footprints in the layout excerpt that follows; sources: Cadence DE-HDL packaged netlist, KiCad conversion of 04192023_DAF0TMB3IC0_F0TG_MB_C_brd_V02_OCP.brd

PC209_1  Q_CAP  1UF 25V 10% X6S  pkg C0402  page 208 : A = SW_P12V_AUX_PVDD11_S3_P0_FLT ; B = GND
PC605_9  Q_CAP  0.1UF 25V 10% X7R  pkg 0402  page 199 : A = PVDDCR_CPU0_P0_VCCS ; B = GND

(kicad_pcb
	(version 20260206)
	(generator "pcbnew")
	(generator_version "10.0")
	(general
		(thickness 1.6)
		(legacy_teardrops no)
	)
	(paper "A4")
	(title_block
		(title "04192023_DAF0TMB3IC0_F0TG_MB_C_brd_V02_OCP.brd")
		(comment 1 "Grand Teton / footprints 4841-4842 of 8354")
	)
	(layers
		(0 "F.Cu" signal "TOP")
		(4 "In1.Cu" signal "GND")
		(6 "In2.Cu" signal "IN1")
		(8 "In3.Cu" signal "GND1")
		(10 "In4.Cu" signal "IN2")
		(12 "In5.Cu" signal "GND2")
		(14 "In6.Cu" signal "IN3")
		(16 "In7.Cu" signal "GND3")
		(18 "In8.Cu" signal "VCC")
		(20 "In9.Cu" signal "VCC1")
		(22 "In10.Cu" signal "GND4")
		(24 "In11.Cu" signal "IN4")
		(26 "In12.Cu" signal "GND5")
		(28 "In13.Cu" signal "IN5")
		(30 "In14.Cu" signal "GND6")
		(32 "In15.Cu" signal "IN6")
		(34 "In16.Cu" signal "GND7")
		(2 "B.Cu" signal "BOTTOM")
		(9 "F.Adhes" user "F.Adhesive")
		(11 "B.Adhes" user "B.Adhesive")
		(13 "F.Paste" user "Package Geometry/Pastemask Top")
		(15 "B.Paste" user "Package Geometry/Pastemask Bottom")
		(5 "F.SilkS" user "Ref Des/Silkscreen Top")
		(7 "B.SilkS" user "Ref Des/Silkscreen Bottom")
		(1 "F.Mask" user "Board Geometry/Soldermask Top")
		(3 "B.Mask" user "Board Geometry/Soldermask Bottom")
		(17 "Dwgs.User" user "User.Drawings")
		(19 "Cmts.User" user "User.Comments")
		(21 "Eco1.User" user "User.Eco1")
		(23 "Eco2.User" user "User.Eco2")
		(25 "Edge.Cuts" user "Board Geometry/Outline")
		(27 "Margin" user)
		(31 "F.CrtYd" user "Package Geometry/Place Bound Top")
		(29 "B.CrtYd" user "Package Geometry/Place Bound Bottom")
		(35 "F.Fab" user "Ref Des/Assembly Top")
		(33 "B.Fab" user "Ref Des/Assembly Bottom")
	)
	(footprint ""
		(layer "F.Cu")
		(at 417.623752 -159.310324)
		(property "Reference" "PC605_9"
			(at 0 0 0)
			(layer "F.SilkS")
			(hide yes)
			(effects
				(font
					(size 1.27 1.27)
				)
			)
		)
		(property "Value" ""
			(at 0 0 0)
			(layer "F.Fab")
			(effects
				(font
					(size 1.27 1.27)
				)
			)
		)
		(duplicate_pad_numbers_are_jumpers no)
		(fp_line
			(start -0.7874 -0.4064)
			(end 0.7874 -0.4064)
			(stroke
				(width 0.1524)
				(type default)
			)
			(layer "F.SilkS")
		)
		(fp_line
			(start -0.7874 0.4064)
			(end -0.7874 -0.4064)
			(stroke
				(width 0.1524)
				(type default)
			)
			(layer "F.SilkS")
		)
		(fp_line
			(start 0.7874 -0.4064)
			(end 0.7874 0.4064)
			(stroke
				(width 0.1524)
				(type default)
			)
			(layer "F.SilkS")
		)
		(fp_line
			(start 0.7874 0.4064)
			(end -0.7874 0.4064)
			(stroke
				(width 0.1524)
				(type default)
			)
			(layer "F.SilkS")
		)
		(fp_line
			(start -0.67945 -0.305054)
			(end -0.12065 -0.305054)
			(stroke
				(width 0.1)
				(type default)
			)
			(layer "F.Fab")
		)
		(fp_line
			(start -0.67945 0.3048)
			(end -0.67945 -0.305054)
			(stroke
				(width 0.1)
				(type default)
			)
			(layer "F.Fab")
		)
		(fp_line
			(start -0.12065 -0.305054)
			(end -0.12065 -0.2794)
			(stroke
				(width 0.1)
				(type default)
			)
			(layer "F.Fab")
		)
		(fp_line
			(start -0.12065 -0.2794)
			(end 0.12065 -0.2794)
			(stroke
				(width 0.1)
				(type default)
			)
			(layer "F.Fab")
		)
		(fp_line
			(start -0.12065 0.2794)
			(end -0.12065 0.3048)
			(stroke
				(width 0.1)
				(type default)
			)
			(layer "F.Fab")
		)
		(fp_line
			(start -0.12065 0.3048)
			(end -0.67945 0.3048)
			(stroke
				(width 0.1)
				(type default)
			)
			(layer "F.Fab")
		)
		(fp_line
			(start 0.120396 0.2794)
			(end -0.12065 0.2794)
			(stroke
				(width 0.1)
				(type default)
			)
			(layer "F.Fab")
		)
		(fp_line
			(start 0.120396 0.3048)
			(end 0.120396 0.2794)
			(stroke
				(width 0.1)
				(type default)
			)
			(layer "F.Fab")
		)
		(fp_line
			(start 0.12065 -0.3048)
			(end 0.67945 -0.3048)
			(stroke
				(width 0.1)
				(type default)
			)
			(layer "F.Fab")
		)
		(fp_line
			(start 0.12065 -0.2794)
			(end 0.12065 -0.3048)
			(stroke
				(width 0.1)
				(type default)
			)
			(layer "F.Fab")
		)
		(fp_line
			(start 0.67945 -0.3048)
			(end 0.67945 0.3048)
			(stroke
				(width 0.1)
				(type default)
			)
			(layer "F.Fab")
		)
		(fp_line
			(start 0.67945 0.3048)
			(end 0.120396 0.3048)
			(stroke
				(width 0.1)
				(type default)
			)
			(layer "F.Fab")
		)
		(pad "1" smd circle
			(at -0.40005 0)
			(size 0 0)
			(layers "F.Cu" "F.Mask" "F.Paste")
			(net "PVDDCR_CPU0_P0_VCCS")
		)
		(pad "2" smd circle
			(at 0.40005 0)
			(size 0 0)
			(layers "F.Cu" "F.Mask" "F.Paste")
			(net "GND")
		)
	)
	(footprint ""
		(layer "F.Cu")
		(at 427.30166 -351.20326 -90)
		(property "Reference" "PC209_1"
			(at 0 0 270)
			(layer "F.SilkS")
			(hide yes)
			(effects
				(font
					(size 1.27 1.27)
				)
			)
		)
		(property "Value" ""
			(at 0 0 270)
			(layer "F.Fab")
			(effects
				(font
					(size 1.27 1.27)
				)
			)
		)
		(duplicate_pad_numbers_are_jumpers no)
		(fp_line
			(start -0.7874 0.4064)
			(end -0.7874 -0.4064)
			(stroke
				(width 0.1524)
				(type default)
			)
			(layer "F.SilkS")
		)
		(fp_line
			(start 0.7874 0.4064)
			(end -0.7874 0.4064)
			(stroke
				(width 0.1524)
				(type default)
			)
			(layer "F.SilkS")
		)
		(fp_line
			(start -0.7874 -0.4064)
			(end 0.7874 -0.4064)
			(stroke
				(width 0.1524)
				(type default)
			)
			(layer "F.SilkS")
		)
		(fp_line
			(start 0.7874 -0.4064)
			(end 0.7874 0.4064)
			(stroke
				(width 0.1524)
				(type default)
			)
			(layer "F.SilkS")
		)
		(fp_line
			(start -0.67945 0.3048)
			(end -0.67945 -0.305054)
			(stroke
				(width 0.1)
				(type default)
			)
			(layer "F.Fab")
		)
		(fp_line
			(start -0.12065 0.3048)
			(end -0.67945 0.3048)
			(stroke
				(width 0.1)
				(type default)
			)
			(layer "F.Fab")
		)
		(fp_line
			(start 0.120396 0.3048)
			(end 0.120396 0.2794)
			(stroke
				(width 0.1)
				(type default)
			)
			(layer "F.Fab")
		)
		(fp_line
			(start 0.67945 0.3048)
			(end 0.120396 0.3048)
			(stroke
				(width 0.1)
				(type default)
			)
			(layer "F.Fab")
		)
		(fp_line
			(start -0.12065 0.2794)
			(end -0.12065 0.3048)
			(stroke
				(width 0.1)
				(type default)
			)
			(layer "F.Fab")
		)
		(fp_line
			(start 0.120396 0.2794)
			(end -0.12065 0.2794)
			(stroke
				(width 0.1)
				(type default)
			)
			(layer "F.Fab")
		)
		(fp_line
			(start -0.12065 -0.2794)
			(end 0.12065 -0.2794)
			(stroke
				(width 0.1)
				(type default)
			)
			(layer "F.Fab")
		)
		(fp_line
			(start 0.12065 -0.2794)
			(end 0.12065 -0.3048)
			(stroke
				(width 0.1)
				(type default)
			)
			(layer "F.Fab")
		)
		(fp_line
			(start 0.12065 -0.3048)
			(end 0.67945 -0.3048)
			(stroke
				(width 0.1)
				(type default)
			)
			(layer "F.Fab")
		)
		(fp_line
			(start 0.67945 -0.3048)
			(end 0.67945 0.3048)
			(stroke
				(width 0.1)
				(type default)
			)
			(layer "F.Fab")
		)
		(fp_line
			(start -0.67945 -0.305054)
			(end -0.12065 -0.305054)
			(stroke
				(width 0.1)
				(type default)
			)
			(layer "F.Fab")
		)
		(fp_line
			(start -0.12065 -0.305054)
			(end -0.12065 -0.2794)
			(stroke
				(width 0.1)
				(type default)
			)
			(layer "F.Fab")
		)
		(pad "1" smd circle
			(at -0.40005 0 270)
			(size 0 0)
			(layers "F.Cu" "F.Mask" "F.Paste")
			(net "SW_P12V_AUX_PVDD11_S3_P0_FLT")
		)
		(pad "2" smd circle
			(at 0.40005 0 270)
			(size 0 0)
			(layers "F.Cu" "F.Mask" "F.Paste")
			(net "GND")
		)
	)
)
